# BARRELEYE-G2-SXM2 RISER BOARD-EVT-X00-BOM-X01-20171102_Final.xls.xlsx — DEPOP (bom)
| FOXCONN TECHNOLOGY GROUP |  |  |  |  |  |  |  |  |  |  |  |  |
| BILL OF MATERIAL |  |  |  |  |  |  |  |  |  |  |  |  |
| REV OF  BOM | X01 | CUSTOMER | <name> |  | CUSTOMER P/N |  | PRODUCT CODE |  | PWA  REV | X00 | DATE | 43041 |
| Sourcing (Single/Sole/Multi) | Critical Commodity (Y or N) | Component Class (1, 2, other) | Customer PSL (Y or N) | Item Number | Foxconn P/N | Customer P/N | Part Description | Manufacturer  Full Name | Manufacturer  Part Number | Qty | RoHS Status | Location |
|  | Y | ND | Y(3) | 1 | 62011U701-015-G | - | CAP,10nF,+/-10%,X7R,6.3V,G,SMD0402 | MURATA ELEC. NORTH AMERICA | GRM155R70J103K | 3 |  | C2242,C2243,C2246 |
|  | Y | 2 | Y(3) | 2 | 620103K00-015-G | - | CAP,1nF,+/-10%,X7R,50V,G,SMD0402 | MURATA ELEC. NORTH AMERICA | GRM155R71H102K | 2 | N | PSTC1,PSTC21 |
|  | Y | 2 | Y(3) | 3 | 620101T02-015-G | - | CAP,100nF,+/-10%,X7R,16V,G,SMD0402 | MURATA ELEC. NORTH AMERICA | GRM155R71C104K | 1 | Y | PSTC12 |
|  | N | Other | Y(4) | 4 | 610101100-017-G |  | RES,1 Ohm,+/-1%,1/10W,G,SMD0603 | KOA SPEER ELECTRONICS, INC. | RK73H1JTTD1R00F | 2 | N | PSTR10,PSTR15 |
|  | N | ND | Y(4) | 5 | 61010G500-017-G | - | RES,10KOhm,+/-1%,1/16W,G,SMD0402 | KOA SPEER ELECTRONICS, INC. | RK73H1ETTP1002F | 2 | N | PSTR11,R1627 |
|  | N | ND | Y(4) | 6 | 610107B00-017-G | K9576 | RES,4.7KOhm,+/-5%,1/16W,G,SMD0402 | KOA SPEER ELECTRONICS, INC. | RK73B1ETTP472J | 29 | N | R1460,R1461,R1491,R1516,R1517,R1544,R1549,R1551,R1553,R1555,R1557,R1565,R1567,R1569,R1571,R1581,R1582,R1583,R1584,R1588,R1589,R1590,R1591,R1603,R1604,R1628,R1629,R1630,R1631 |
|  | N | ND | Y(4) | 7 | 610107A00-017-G | - | RES,0 Ohm,+/-5%,1/16W,G,SMD0402 | KOA SPEER ELECTRONICS, INC. | RK73Z1ETTP | 24 | N | R1501,R1502,R1504,R1505,R1550,R1552,R1556,R1559,R1560,R1561,R1562,R1570,R1587,R1592,R1593,R1594,R1595,R1596,R1598,R1605,R1609,R1620,R1621,R1623 |
|  |  |  | Y(4) | 8 | 61010KJ00-017-G |  | RES,3.3KOhm,+/-5%,1/16W,G,SMD0402 | KOA SPEER ELECTRONICS, INC. | RK73B1ETTP332J | 2 | N | R1607,R1614 |
